M48
INCH,TZ
T01C.012
T02C.016
T03C.035
T04C.04
T05C.041
T06C.138
T07C.158
T08C.199
T09C.099
T10C.115
T11C.126
T12C.14
T13C.142
;LEADER: 12 
;HEADER: 
;CODE  : ASCII 
;FILE  : 12433-1M-1-4.drl for board 12433-1M.brd ... layers TOP and BOTTOM
;T01 Holesize 1. = 12.000000 Tolerance = +0.000000/-0.000000 PLATED MILS Quantity = 500
;T02 Holesize 2. = 16.000000 Tolerance = +0.000000/-0.000000 PLATED MILS Quantity = 1583
;T03 Holesize 3. = 35.000000 Tolerance = +0.000000/-0.000000 PLATED MILS Quantity = 18
;T04 Holesize 4. = 40.000000 Tolerance = +0.000000/-0.000000 PLATED MILS Quantity = 36
;T05 Holesize 5. = 41.000000 Tolerance = +0.000000/-0.000000 PLATED MILS Quantity = 104
;T06 Holesize 6. = 138.000000 Tolerance = +0.000000/-0.000000 PLATED MILS Quantity = 6
;T07 Holesize 7. = 158.000000 Tolerance = +0.000000/-0.000000 PLATED MILS Quantity = 2
;T08 Holesize 8. = 199.000000 Tolerance = +0.000000/-0.000000 PLATED MILS Quantity = 5
;T09 Holesize 9. = 99.000000 Tolerance = +0.000000/-0.000000 NON_PLATED MILS Quantity = 4
;T10 Holesize 10. = 115.000000 Tolerance = +0.000000/-0.000000 NON_PLATED MILS Quantity = 6
;T11 Holesize 11. = 126.000000 Tolerance = +0.000000/-0.000000 NON_PLATED MILS Quantity = 4
;T12 Holesize 12. = 140.000000 Tolerance = +0.000000/-0.000000 NON_PLATED MILS Quantity = 4
;T13 Holesize 13. = 142.000000 Tolerance = +0.000000/-0.000000 NON_PLATED MILS Quantity = 12
%
G90
T01
X89500Y49500
X63500Y63500
X64000Y67553
X64500Y53000
X70454Y60031
X74000Y60500
X75000Y67500
X79000Y65500
X81500Y75500
X84500Y56500
X88253Y65500
X91000Y97000
X91500Y88500
Y92500
X92500Y73000
X97000Y51500
X98500Y73000
X99500Y61000
X109000Y76500
X109500Y62000
X115000Y76500
X115500Y59500
X149500Y52000
X112000Y101000
X104500
X93900Y111800
X93500Y101500
X93000Y107000
X59600Y125800
X32425Y177900
X39300Y175500
Y181100
X43400Y174325
X43700Y181200
X47800Y199200
X49924Y153261
X52500Y175200
X52700Y162300
X53000Y171500
X53400Y191300
X53500Y199700
X60350Y151950
X63500Y179300
X64000Y199700
X64400Y183400
X65000Y166300
X70500Y190200
X75300Y155300
X201500Y165000
X127200Y246000
X122100Y230100
X117600Y234900
X85676Y231100
X77900Y229034
X75300Y211300
X74800Y231800
X72100Y221700
X71400Y208150
X70600Y217600
X69900Y236600
X69400Y226100
X65200Y207850
X65000Y241500
Y235400
X61300Y229400
X57424Y232974
X54400Y217000
X54200Y220700
Y207850
X52500Y248500
X51700Y234800
X49700Y209700
X48500Y248600
X42720Y233990
X41100Y231000
X38000Y228500
X70600Y250500
X68000Y268000
X60300Y275700
X58936Y256289
X57500Y268500
X54000Y275600
X50800Y266400
X45800Y277800
X43400Y272300
X42500Y260200
Y254100
X36000Y260386
X34200Y284800
X32675Y299500
X32600Y290500
X26450Y274750
X21600Y333800
X23100Y342400
X25500Y321200
X29500Y343500
X23400Y353500
X29500Y410500
X34000Y448000
X78000Y429500
X122500Y441000
X135500
X146960Y432400
X191400Y432405
X165300Y481100
X142000Y478500
X108100Y477650
X33200Y468900
X14000Y476000
X5304Y528900
Y548800
X28800Y533700
X46000Y516000
X46500Y511000
X51000Y529500
X52100Y513100
X71445Y532192
X72397Y528297
X77800Y540300
X87700Y528000
X91300Y528200
X102700Y541000
X108900Y541300
X132500Y539621
X144000Y509500
X147000Y529900
X159850Y541800
X162500Y527900
X166100
X182588Y542288
X160000Y562500
X159250Y590250
X156300Y552100
X154600Y581500
X147900Y588100
X145800Y594400
X142500Y550000
X142100Y581400
X137000Y589900
X135000Y561500
X134600Y586700
X133500Y575500
Y582000
X129000Y597000
X128900Y580500
X124900Y582000
X124200Y568400
X122300Y575000
X121000Y581500
X119800Y568300
X116000Y596900
X115300Y551800
X113655Y599363
X110400Y550800
X106300Y553200
X101000Y583000
X96000Y588000
X92200Y553800
X91300Y577000
X89000Y595000
X88000Y586500
X87000Y591000
X78400Y583700
X70350Y558850
X66000Y550500
X65000Y561500
X63400Y581400
X54600Y573400
X49700Y568900
X33450Y574300
X29500Y586500
X27000Y573800
X25148Y570800
X23450Y577491
X5094Y574500
X84200Y643865
X87000Y648000
X131135Y639554
X174196Y628196
X202210Y638500
X202500Y666000
X201500Y691500
X165433Y692372
X161500Y691700
X161000Y674000
X157500Y664500
X155200Y679500
X150978Y687775
X150700Y691700
X149000Y677000
X142648Y665429
X139200Y653900
X138900Y650100
X134600Y665600
X122500Y653650
X118127Y663400
X117400Y653100
X114000Y663350
X109005Y665890
X100200Y663900
X98000Y698500
X93000
X86597Y681103
X83850Y678109
X82000Y652000
X78494Y697835
X76100Y686900
X75571Y692496
X66200Y653500
X64000Y666600
X60900Y670200
X60500Y682540
X57684Y697639
X53000Y673500
Y695100
X52500Y682500
X44500Y697500
X43388Y694286
X39800Y681400
X4594Y714000
Y749000
X46500Y705500
X49500Y703500
X69000Y726800
X71500Y735500
X73000Y728000
X73500Y732000
X86500Y723500
X88500Y700000
X91250Y704700
X98000Y703000
Y708000
X105500Y702500
X106000Y709000
X113500Y729000
Y736000
Y747000
Y721000
X114500Y700500
X119500Y739500
Y746500
X122500Y700500
X130000Y746000
Y700500
X146000Y726000
Y738000
X147000Y703000
X153192Y705890
X161500Y747500
X161600Y739800
X165900Y717300
X170000Y745500
X175100Y710000
X201500Y726500
X202500Y755500
X201500Y777000
X201389Y797000
X166500Y775500
X166000Y751500
Y760000
X161500Y778000
Y759000
Y768000
X158600Y752600
X146000Y755000
Y782500
Y796500
Y765500
X130000Y753000
Y764000
X119500Y757500
X113500Y756000
X51200Y827000
X57500Y844500
X61207Y828350
X72400Y822900
X98900
X100300Y841000
X106404Y840700
X114900Y824100
X118700Y840700
X146000Y824000
X146500Y812000
X162000Y817500
X168000Y830000
X174000Y834500
X202500Y822000
Y846500
X202000Y859500
Y890000
Y875000
X180000Y856000
Y872500
X179500Y884000
X157800Y898000
X113400Y862200
X111500Y851600
X107164Y862285
X102300Y863438
X101500Y874200
X67200Y888800
X64600Y882700
X61600Y885200
X59500Y881600
X57500Y890300
X56000Y885500
X55700Y880000
X49600Y889400
X54300Y915500
X147500Y900500
X179800Y941400
X179900Y925700
Y900900
X180000Y912500
X201500Y931500
X202000Y918000
X202210Y903500
X202500Y945500
Y962000
Y977500
X201500Y991000
X180500Y973200
X180000Y960400
X163200Y985200
X163100Y978600
X155000Y974500
X152747Y952474
X150500Y976500
X149772Y954121
X146500Y953030
X143000Y953032
X125400Y983600
Y992000
X97300Y990800
X94000Y971800
X83500Y976300
Y972800
X83000Y979800
X70800Y990500
X57500Y987800
Y984300
X54000Y996500
X51000Y1018000
X53500Y1025500
X53800Y1006200
X54500Y1035500
X56000Y1021500
X104000Y1049500
X127200Y1015200
X149800Y1008700
X151500Y1030500
X153500Y1033500
X155500Y1030000
X163000Y1042500
X179000Y1005000
X201500Y1019000
X202000Y1037000
X202500Y1006000
X202000Y1052000
X201500Y1082500
X201389Y1067000
X159500Y1062000
X104000Y1062500
X64500Y1099000
X37500Y1099823
X82094Y1112500
X195000Y1112000
X201500Y1147000
X202500Y1179000
X105000Y1181000
X73163Y1158780
X71100Y1171000
X70500Y1161500
X68800Y1178800
X202000Y1212000
Y1246000
X119000Y1255968
X119500Y1261000
X202500Y1280000
X201500Y1310000
X200700Y1348500
X201700Y1388300
X201500Y1359500
X155900Y1397100
X146500
X125000Y1398500
X111000Y1394000
X44500Y1380500
X39400Y1381300
X5094Y1354500
X45000Y1428000
X45500Y1400000
X89000Y1428171
X100860Y1402260
X110000Y1429500
X125100Y1402500
X128700Y1408000
X131174Y1412700
X132000Y1436500
X134500Y1420000
X135601Y1416200
X139900Y1415100
X142500Y1420500
X151500Y1438500
X169000Y1426750
X201389Y1425500
X201500Y1413000
X202400Y1444000
X202210Y1462000
X158500Y1466500
X157500Y1454800
X153500Y1496500
X147500Y1498000
X142000Y1494800
X132300Y1491100
X112750Y1491250
X83200Y1455500
X80000Y1472000
X26700Y1529800
X36400Y1523400
X109000Y1506500
X113000
X117000
X121000
X125000
X128999Y1506499
X133000Y1505500
X135008Y1508245
X202000Y1537500
X202210Y1554000
X201500Y1569000
X187500Y1559500
X177500Y1569500
X143518Y1567520
X108500Y1569000
X67700Y1568700
X38400Y1596700
X28000Y1596800
X10500Y1648800
X13300Y1644300
X31400Y1648200
X42700Y1606000
X43300Y1646600
X43500Y1620700
X83050Y1616000
X83000Y1619703
X113200Y1619300
Y1622800
X141300Y1625000
X141500Y1621600
X169876Y1626303
X173270Y1626517
X192500Y1648000
X192650Y1641500
X196500Y1606500
X191700Y1652700
X45500Y1690000
X44500Y1678000
X44100Y1685200
X43600Y1668300
X42500Y1673000
X41500Y1692000
X35500Y1670500
X34000Y1691500
X13300Y1689600
X19200Y1707000
X19542Y1710518
X29100Y1721550
X40300Y1703900
X52500Y1756000
X45300Y1776300
X26750Y1791100
X25000Y1763800
X27400Y1899400
X38700Y1893800
X41500Y1889500
X47000Y1886200
X55900Y1881500
X57900Y1899800
X60300Y1892300
X62000Y1877000
X65300Y1886600
X151900Y1891400
X152500Y1883100
X200500Y1876500
X201200Y1890500
X201100Y1908800
X184500Y1920500
X177700Y1912800
X176700Y1923900
X170000Y1920500
X162100Y1912000
X157900Y1923100
X146300Y1913700
X142400Y1923800
X133500Y1906500
X128900Y1923300
X104600Y1923400
X91100Y1922800
X79900Y1923000
T02
X20000Y6000
X8594Y6500
X17000Y36500
X29500Y53000
X5594Y53500
Y87000
X26000
X14500Y100500
X4500Y105500
X14500Y112500
X4594Y120500
X23500Y124000
X15000Y131500
X5000Y137500
X15500Y143500
X5594Y153500
X4500Y170500
X16500Y175000
X27000Y182000
X14000Y184000
X4594Y187500
X22500Y190000
X29700Y191400
X12500Y197500
X29000Y200500
X4500Y202500
X24000Y212000
X13000Y212500
X5000Y221000
X13500Y230500
X4594Y234000
X21500Y241500
X13000Y244000
X5000Y247500
X28050Y256950
X6094Y257000
X12500Y266500
X19721Y267203
X5500Y269500
X5094Y278000
X13500Y279000
Y295000
X5500Y295500
X13500Y303500
X5594Y312000
X13000Y321000
X4900Y328000
X5304Y342500
X4800Y356200
X23700Y363900
X29500Y364500
X27000Y371000
X6500Y375000
X27000Y377500
Y384000
Y389500
X4594Y396500
X5000Y408500
X23800Y410700
X4594Y421000
X26000Y432500
X5304Y434500
X26500Y440000
X5304Y440500
Y444500
X4700Y458200
X5094Y469500
X5000Y486500
Y495000
X13510Y597990
X5094Y600000
X18000Y608000
X6000Y612000
X14000Y614000
X4594Y625000
X6000Y646000
X26000Y656500
X14000Y659000
X5304Y661000
X23000Y677500
X8000Y678000
X5594Y688500
X20000Y696000
X6000Y698000
X28000Y706000
X6000Y706500
X18000Y712000
X6000Y722000
X18000Y724000
X6000Y730500
X26000Y732000
X18000Y732500
X22000Y746000
X27000Y750000
X24000Y756000
X5594Y778000
X16100Y794600
X6500Y799000
X9500Y804000
X10000Y811500
X16000Y814000
X6094Y819500
X16000Y828000
X26053Y828247
X4500Y833500
X16000Y842000
X5594Y844500
X24000Y846000
X24500Y853500
X16000Y856000
X4500Y857500
X23053Y861247
X5594Y869000
X18000Y870000
X5000Y883500
X18000Y884000
X18500Y896500
X5094Y897500
X16000Y906000
X4500Y913000
X18000Y920000
X5304Y926000
X18000Y934000
X26053Y938247
X4500Y941500
X16000Y948000
X4594Y954000
X16000Y962000
X4500Y970000
X25053Y971247
X16000Y976000
X5594Y984500
X16000Y990000
X28000Y992000
X4500Y997000
X16000Y1000000
X26000Y1010000
X4594Y1013500
X16000Y1014000
X27553Y1029247
X4500Y1029500
X16000Y1032000
X4594Y1041500
X16000Y1046000
X6000Y1058000
X14000Y1060000
X28000Y1072000
X14000Y1074000
X5094Y1074500
X14000Y1086000
X26100Y1088600
X6000Y1096000
X27218Y1097000
X14000Y1100000
X16000Y1110000
X6000Y1118000
X16000Y1124000
X26600Y1132400
X16000Y1134000
X6000Y1138000
X16000Y1148000
X6000Y1152000
X24553Y1153247
X16000Y1162000
X4594Y1169500
X16000Y1176000
X24000Y1180000
X5304Y1208000
X22000Y1232000
X8500Y1237000
X16000Y1244000
X6000Y1252000
X16000Y1262000
X28000Y1266000
X5094Y1268500
X12000Y1274000
X17700Y1283000
X28000Y1286000
X12000Y1294000
X28000Y1300000
X6500Y1302000
X19800Y1315400
X6000Y1318000
X28000Y1320000
X13500Y1365000
X8000Y1368000
X7500Y1376500
X4594Y1382000
X5304Y1409400
X4594Y1435500
X4800Y1460700
X4600Y1484800
X29500Y1495800
X5304Y1504100
Y1522100
Y1540500
X26900Y1547900
Y1559100
X26600Y1570100
X5304Y1576200
X26700Y1579800
X4594Y1607500
Y1632000
X7500Y1640200
X5304Y1659000
X19250Y1663100
X29000Y1671000
X4700Y1676100
X4594Y1691000
X13900Y1706200
X4900Y1708000
X5304Y1723500
X13100Y1728900
Y1742600
X4594Y1751000
X12600Y1753800
X12900Y1765200
X4594Y1775000
X12500Y1782500
X12600Y1792800
X4594Y1799500
X5900Y1814100
X4594Y1826500
X24200Y1836700
X14500Y1842000
X4594Y1850000
X15000Y1854900
X12800Y1863700
X5000Y1864100
X18600Y1871400
X27500Y1874500
X4594Y1878500
X24500Y1884000
X4594Y1902000
X5094Y1921000
X24800Y1926500
X13100Y1933900
X4500Y1936000
X15500Y1942500
X5094Y1944500
X16100Y1950700
X12500Y1959000
X6500Y1962000
X25000Y1962500
X34500Y1963200
X55300Y1959100
X41100Y1957500
X49053Y1951747
X43500Y1945000
X35000Y1933500
X45100Y1933400
X54000Y1928500
X35300Y1925300
X46000Y1923000
X36500Y1900500
X54500Y1889500
X31500Y1878500
X39700Y1869700
X45500Y1865000
X46700Y1857700
X46500Y1850200
X39700Y1846600
X36000Y1835500
X44500Y1833500
X44400Y1821400
X39179Y1792306
X42000Y1784400
X38800Y1775000
X56500Y1769300
X36700Y1764700
X53000Y1750500
X41600Y1746900
X48400
X44900Y1740300
X55500Y1735500
X30000Y1731000
X44600Y1724400
X55500Y1723500
X56000Y1712500
X44900Y1706800
X56000Y1704500
X42500Y1699500
X56000Y1695000
X59500Y1667000
X53500Y1659000
X54000Y1646500
X43200Y1634800
X55000Y1634000
X55400Y1613300
X58500Y1607700
X50600Y1601300
X55300Y1601100
X50600Y1595300
X55300Y1595100
X44400Y1592100
X50600Y1589300
X55300Y1589100
X33100Y1587400
X50600Y1582800
X55300Y1582600
X38300Y1579600
X54500Y1574000
X37900Y1570000
X57000Y1568500
X45300Y1563600
X57500Y1562000
X38300Y1561800
X38800Y1541700
X54300Y1541200
X46600Y1541100
X59500Y1541000
X45900Y1532800
X45400Y1523800
X53500Y1519000
X58500
X43300Y1518500
X49500Y1505000
X42700Y1500000
X46500Y1484900
X34000Y1477600
X59000Y1472000
X34000Y1465900
X58100Y1459300
X49100Y1448400
X59000Y1444500
X42600Y1444200
X53100Y1430700
X49000Y1413300
X58800Y1412400
X39500Y1407900
X30800Y1403900
X56700Y1400100
X31500Y1397500
X32000Y1391500
X48900Y1390500
X55600Y1381700
X52500Y1368500
X44000Y1340000
X38000Y1334000
X54000Y1330000
X44000Y1326000
X50000Y1318000
X34000Y1312000
X58000
X44000Y1306000
X40000Y1298000
X52000Y1296300
X58000Y1292000
X42000Y1290000
X40000Y1278000
X58000Y1272000
X42000Y1266000
X50100Y1261500
X58000Y1250000
X50000Y1244000
X42000Y1242000
X30000Y1240000
X51800Y1231600
X39500Y1231000
X58000Y1222000
X31500
X46000Y1218000
X58000Y1206000
X44000Y1194000
X54000Y1184000
X40000Y1156000
X34000Y1144000
X40000Y1136000
X37500Y1118900
X32000Y1114000
X39300Y1105800
X34000Y1102000
X33550Y1080100
X34000Y1072000
X33600Y1029900
X31600Y1024300
X34000Y1017500
Y1008000
X37700Y991600
X34000Y984000
Y974500
X55500Y968000
X33500Y962500
X55500Y955500
X33500Y953000
X34000Y944000
X56500Y940000
X34000Y934500
X41000Y931899
X37500Y912000
Y907500
X40900Y901500
X32000Y886000
X47000Y877600
X32000Y872000
Y858000
X48100Y853400
X46000Y848000
X32000Y844000
X38000Y834000
X46000
X45600Y827500
X38000Y820000
X30500Y819500
X48000Y816000
X42000Y802000
X47600Y796800
X42000Y788000
X44000Y782000
X30000
X50000Y749000
X31000Y747000
X40000Y746500
X36000Y730000
X46000Y726000
X50000Y712500
X31000Y700500
X56710Y681069
X43281Y674991
X39096Y674917
X32000Y666000
X40000Y659000
X56800Y576950
X34100Y566600
X36000Y554000
X51700Y522500
X42500Y493000
X50100
X46000Y490500
X58100Y431900
X58000Y426000
Y417500
Y408000
Y400000
Y390000
X51900Y145700
X51700Y131700
X30800Y130300
X37000Y124000
X52000Y115600
X34400Y95300
X51500Y53000
X32000Y40000
X43000Y27000
X49000Y18500
X40594Y6000
X31500Y5500
X53000Y5000
X63594Y7000
X64000Y17000
X63594Y25500
X64500Y40000
X74000Y45000
X85000
X63098Y119103
X71000Y131859
X62598Y141103
X73500Y146000
X60800Y147700
X86000Y152000
X69000Y153000
X68000Y286000
X86000Y296000
X68000
X76000
X68000Y304000
Y312000
Y320000
X74000Y390000
X66000
X74000Y400000
X66000
X74000Y408000
X66000
X81000Y410500
X86400
X66000Y418000
X74000
X73700Y423000
X66000Y426000
X88500Y426500
X84500Y433000
X68500Y434300
X63096Y434540
X89800Y446000
X64000Y446500
Y451000
X89800Y452900
X64000Y455500
X89800Y459000
X64000Y460000
X63300Y464400
X89800Y464800
X62600Y468500
X62500Y472900
Y477000
X78200Y481700
X82000Y483600
X71900Y501000
X78200
X85000Y506400
X78500Y506700
X71800Y506900
X84500Y514400
X72000Y514800
X78000
X79400Y521800
X72100
X74942Y530983
X79122Y565700
X69800Y574200
X79458Y578758
X87595Y581300
X72500Y595900
X88967Y659749
X86443Y662853
X84504Y666353
X80900Y668400
X74100Y669398
X87310Y676796
X69100Y698006
X71800Y701300
X82000Y806500
X82500Y814000
X78300Y832600
X81500Y837500
X87000Y839500
X77600Y849100
X79000Y857000
X62500Y862000
X77000Y863000
Y871500
X61500Y876500
X78000Y878500
X83400Y878600
X78300Y893900
X85500Y903000
X77500Y907000
X70000Y914500
X85500Y915000
X77500Y917000
X62500Y924500
X70000Y925500
X76500Y927000
X86500Y932000
X75500Y936500
X61500Y938500
X69500Y939000
X81500Y940000
X88500Y940500
X64000Y980500
X87000Y997500
X76400Y999100
X87000Y1063000
X77293Y1129729
X74000Y1132000
X67302Y1133490
X79044Y1144112
X78292Y1148041
X66000Y1149500
X64500Y1165700
X89000Y1167400
X61000Y1173000
X60000Y1194000
X84000Y1352000
X72000Y1360000
X61000Y1363500
X83800Y1365900
X71800Y1373900
X70500Y1378500
X61500Y1380000
X81500Y1382000
X60900Y1390500
X83800Y1391900
X72900Y1393600
X69400Y1402900
X81500Y1404000
X74900Y1408800
X89700Y1409700
X81500Y1416500
X68800Y1417800
X75600Y1420300
X60600Y1423600
X76200Y1430700
X87200Y1431900
X66500Y1433500
X87300Y1436000
X79000Y1436400
X87200Y1440000
X70400Y1444500
X87700Y1446500
X77000Y1449000
X86900Y1451000
X68500Y1454600
X74500Y1461800
X83500Y1469500
X72300Y1469800
X72700Y1480500
X63000Y1482300
X85000Y1490000
X73000Y1491200
X64100Y1495400
X72000Y1514000
X85200Y1515000
X87900Y1523400
X80000Y1531600
X73900Y1535900
X68700Y1603900
X71600Y1607700
X86000Y1634000
X64000
X76000
X64500Y1646000
X76000
X86000
X64500Y1658500
X75500Y1659500
X86000
X70000Y1668000
X86000Y1669000
X75500Y1679000
X86000
X69000Y1684500
X80500
X62500Y1691500
X72500Y1699000
X62500Y1700000
X86500Y1700110
X62500Y1709000
X86500Y1713610
X72500Y1717000
X65000Y1724000
X86500Y1726000
X60000Y1730000
X72500Y1733000
X65000Y1735000
Y1742500
Y1749000
X64500Y1758500
X71500Y1760000
X79000Y1766500
X65000Y1768000
X87000Y1774110
X88500Y1785000
X65000Y1790000
X86500Y1793110
X72000Y1798000
X64500Y1801500
X81000Y1802000
X64500Y1812000
X73000Y1813000
X64500Y1821500
X72500Y1830000
X64000Y1834000
X75500Y1838500
X64000Y1844500
X85100
X73000Y1847000
X85700Y1852300
X63500Y1856000
Y1863000
X61500Y1922500
X63500Y1928000
X63594Y1935500
X61600Y1954700
X63500Y1963000
X118000Y1922000
X116948Y1892000
X106500Y1862500
X114500
X99500
X108500Y1851610
X97000Y1850500
X114000Y1843500
X110500Y1801000
X119500Y1796500
X97500Y1796000
X107768Y1789110
X98000Y1786000
X108268Y1777300
X97500Y1775500
X111500Y1768500
X119500Y1760000
Y1747110
X117500Y1732000
X108500Y1727000
X119500Y1725110
X109500Y1719500
X98500Y1717000
X119500Y1710110
X110000Y1709500
X99000Y1707000
X109500Y1699000
X119500Y1696610
X98500Y1696500
X112500Y1685000
X103000
X91000
X97500Y1679500
X107500Y1679000
X117500
X97000Y1669000
X107000
X117500
Y1659500
X107000
X97000
X108000Y1646000
X118000
X96000
X96500Y1634000
X106000
X117000Y1633500
X116000Y1612000
X113500Y1605500
X94500
X104000
X116000Y1600000
Y1592000
Y1584000
Y1576000
X115900Y1569700
X102000Y1568000
X94000
X114000Y1564000
X102000Y1562000
X94000
X114000Y1558000
X102000Y1556000
X94000
X114000Y1552000
X102000Y1550000
X94000
X114000Y1546000
X102000Y1544000
X111500Y1537500
X119000Y1529500
X93000Y1518700
X94000Y1514000
X97000Y1503100
X91300Y1488600
X99170Y1485790
X93500Y1482700
X103700Y1470300
X95500Y1468000
X117195Y1456070
X99800Y1455600
X113024Y1452079
X117024Y1452000
X117122Y1448001
X109500Y1438000
X117000Y1435200
X98500Y1428400
X94000Y1427800
X110000Y1418000
X99600Y1416500
X105500Y1415000
X97500Y1412000
X93600Y1407100
X93800Y1393200
X100500Y1389000
Y1384500
X93800Y1379900
X114000Y1376000
X114500Y1370500
X94000Y1366000
X115800Y1363900
X93800Y1353900
X116000Y1350000
X94000Y1340000
X113800Y1331900
X90800Y1331200
X97800Y1327900
X114000Y1318000
X91500Y1314500
X99500Y1310000
X114500Y1296500
X92000Y1295500
X99500Y1294000
X113800Y1287900
X98000Y1282000
X114000Y1274000
X119000Y1269000
X99000Y1265500
X92000Y1254000
X117500Y1251000
X112000Y1250500
X119300Y1245400
X103000Y1244900
X112000Y1244500
X92000Y1241500
X119500Y1231500
X103500Y1229000
X91500
X104500Y1219500
X119300Y1219400
X92000Y1214500
X104500Y1208000
X119500Y1205500
X91500Y1200000
X105000Y1196000
X119300Y1191400
X94000Y1189000
X119500Y1177500
X118500Y1166000
X110500Y1112000
X115000Y1108500
X104500Y1095000
X109000Y1083500
X116500Y1076000
X103500Y1073500
X110500Y1064500
X95400Y1064100
X91400
X116500Y1062500
X110500Y1051000
X116500Y1049000
X103500Y1042000
X110500Y1041500
X116500Y1035500
X111500Y1030000
X103500Y1028500
X117500Y1023500
X97250
X111500Y1020000
X104000Y1014000
X117000Y1008500
X106500
X114800Y1005000
X95500Y999000
X105500Y996000
X119000Y975000
X108500Y971000
Y964000
X105000Y958000
X99000Y953000
X110000Y949500
X117529Y948844
X115500Y930000
X93000Y925500
X115000Y920000
X107000Y918000
X96500Y916500
X94000Y910500
X113500Y909500
X103500
X96053Y903247
X116053
X107000Y903000
X102500Y893500
X117500Y893000
X90000
X95500Y841500
X90500Y831500
X115000Y813000
X114500Y805500
X107000Y802400
X114000Y800000
X107000Y798200
X106882Y794201
X113500Y792500
X115200Y784200
X115000Y773200
X116500Y752000
X115000Y704500
X108500Y695500
X103500
X99001Y694866
X119576Y687008
X98000Y674327
X102913Y673973
X107113Y674001
X119000Y673300
X100600Y670600
X90674Y663367
X108200Y655825
X112800Y653500
X90630Y602020
X103100Y587600
X117000Y530000
X100000Y519100
X110800Y512600
X100000Y512000
X110800Y506600
X100000Y506000
X110800Y500600
X100000Y500000
X110800Y494600
X100000Y494000
X110800Y488600
X100000Y488000
X110800Y482600
X99800Y482000
X111500Y473000
X99500
X117000Y471500
Y466000
Y460500
Y455000
Y449000
X98000Y426500
X102500
X107000
X111200Y426400
X118000Y424000
Y414000
X91900Y410500
X110500Y406500
X105500
X101500
X118000Y404000
Y396000
X101300Y390100
X111500Y390000
X105500
X118000Y386000
X94000Y320000
Y312000
X102000
X94000Y304000
X104000
X114000Y296000
X96000
X106000
X95000Y155000
X105000
X118000Y154500
X105000Y143000
X95000
X118000Y142500
X95000Y134000
X105000Y125000
X95000
X118000Y124500
X119000Y109500
X105000Y55000
X118000Y54500
X95000Y45000
X115000
X105000
X125000
X145000
X135000
Y50000
Y70000
X124000Y74500
X128500Y89000
X128700Y104200
X127700Y119200
X137200Y123600
X146500Y131859
X131000Y138100
Y150100
X147600Y150900
X129000Y160100
X138800Y162100
X137900Y171400
X130900Y259100
X131800Y289700
X142000Y291000
X141300Y298100
X143400Y318700
X143300Y343400
X134000Y386000
Y396000
Y404500
Y414000
Y424000
X145500Y427000
X142000Y432000
X130000
X131000Y447000
X136000
X122500Y450500
X130500Y454000
X135500
X122500Y457500
X135500Y461000
X130500
X122500Y463500
X130500Y468000
X135500
X122500Y469500
X135500Y474500
X130500
X121500Y475500
X129000Y485500
X136500
X120000
X144000Y486182
X137000Y493000
X129000Y493500
X144000
X120000
X144000Y501500
X120000
X137000
X129000
Y509500
X120000
X137000Y510000
X129000Y517500
X137500
X120000
X144000
X129000Y523500
X137500
X120000
X144600Y533800
X147500Y551500
X141800Y559250
X140700Y576600
X145500Y604000
X148995Y658568
X134100Y674500
X121500Y683500
X120702Y690847
X124800Y696600
X129800Y696800
X120000Y717500
X120500Y732500
X125000Y734000
X130000Y736500
X125500Y741500
X125000Y751000
Y758500
X121000Y767900
X129000Y774500
X121000Y776000
X129500Y782000
X121500Y783500
X129500Y792500
X122500
X130000Y800000
X123000
Y808500
X129800Y813500
X123500Y816000
X124500Y825100
X129200Y830400
X134500Y840500
X123500Y842500
X140500Y846500
X145500Y856500
X124500Y858000
X125000Y868500
X124500Y876500
X137500
X145500Y885000
X134500Y885500
X126000Y892500
X135000Y893000
X146000
X127000Y903000
X137500
X135500Y909000
X124000
X143000Y910500
X120000Y916000
X135000Y918000
X144000Y919500
X125500Y920000
X135500Y927500
X144000Y929000
X126000Y930000
X133500Y938000
X141000Y938500
X125500Y944000
X126000Y954000
X124618Y959244
X130500Y966000
X125000Y967000
X136500
X124000Y971500
X135000Y975500
X134000Y990500
X146800Y1018900
X143900Y1022700
X120000Y1102000
Y1108000
X147500Y1165500
Y1186000
Y1221500
X146500Y1241500
X147000Y1265500
X124000Y1270000
X123800Y1283900
X147500Y1288000
X124000Y1298000
X147500Y1311000
X123800Y1311900
X124000Y1324000
X147500Y1332000
X123800Y1337900
X147000Y1348000
X124000Y1352000
X123800Y1365900
X147500Y1366500
X124000Y1376500
X147000Y1377000
X146500Y1417619
X132200Y1424800
X137000Y1429200
X133799Y1440699
X121338Y1452021
X149686Y1460007
X126600Y1461500
X148300Y1465000
X133500Y1467100
X124500Y1524000
X136000Y1528000
X148000
X129000Y1535000
X136000Y1536000
X122000Y1538000
X136000Y1542000
X148000
X129000Y1542500
X122000Y1546000
X136000Y1548000
X129000Y1549000
X148000Y1550000
X122000Y1552000
X136000Y1555000
X129000Y1555500
X122000Y1558000
X148000
X136000Y1562000
X129000Y1562500
X122000Y1564000
X148000
X128000Y1568000
X136000
X121800Y1569929
X122000Y1576000
Y1584000
Y1592000
Y1600000
X148000Y1606000
X138500
X128000
X122000Y1612000
X146000
X149000Y1632500
X127500Y1633000
X138000Y1634000
Y1646000
X148000
X127000
X127500Y1659500
X137500
X148500Y1660000
X127500Y1669000
X141500Y1673000
X125000Y1679000
X122000Y1685500
X139000Y1696500
Y1712500
X138500Y1727500
X139000Y1800500
X120000Y1811500
X138000Y1824000
X120500Y1836500
X138500Y1839500
X120500Y1850500
X139000Y1851000
X122500Y1862500
X132000Y1892000
X124500Y1892403
X161000Y1901500
X160500Y1877500
X173000Y1852610
X161500Y1852500
X151500Y1851110
X179000Y1798500
X155500
X166500Y1798000
X152000Y1790110
X172768
X162000Y1790000
X156500Y1782000
X169000Y1781500
X173268Y1776000
X162500Y1773000
X152500Y1771110
X152000Y1725610
X158500Y1716500
X167500Y1716000
X152000Y1710610
X158500Y1705000
X168500
X152000Y1697110
X174268
X163000Y1697000
X170000Y1659500
X178000
X159000
X158000Y1646000
X166000
X176000
X167500Y1632500
X159000
X176000Y1632000
X164000Y1606000
X156000
X172000
X150500Y1600000
X156500
X150500Y1591000
X156500
X156000Y1582000
X150500
X156000Y1576000
X150000
Y1570000
X156000
X166898Y1567102
X154000Y1564000
X161300Y1563100
X169500Y1561500
X170000Y1555000
Y1548500
X161400Y1543500
X170000Y1541000
X168500Y1533500
Y1526000
X174000Y1522000
Y1515500
X174500Y1509500
Y1503500
X152500Y1456000
X173375Y1432500
X164500Y1299500
X165000Y1264500
X161500Y1227500
X178644Y1202519
X163344Y1181200
X155000Y1130500
X177102Y1129800
X171502Y1129547
X155000Y1125000
Y1120000
X154600Y1111000
X158595Y1110789
X170000Y1103000
X157000Y1101500
X165000Y1097000
X170000Y1089500
X159500Y1087500
X173000Y1082000
X166000Y1080000
X158500Y1075800
X175000Y1072500
X171000Y1068000
X160500Y1067000
X175000Y1059000
X160500Y1053500
X171000Y1046000
X164700Y1033600
X171000Y1032500
X166300Y1021300
X176000Y1018500
X174000Y1012400
X153500Y941000
X154500Y926500
X154700Y909700
X156500Y889000
X156300Y877200
X157500Y858000
X177500Y826500
X171500Y819500
X177500Y812000
X163500Y805500
X178000Y797500
X169000Y795500
X175000Y786500
X165000Y786000
X173500Y777500
Y764000
X172000Y757500
X169100Y722100
X176000Y679000
X165500Y677500
X176000Y665500
X151432Y661741
X162300Y659100
X167300Y653800
X159700Y652000
X165600Y630269
X170349Y619949
X152700Y618803
X175800Y617635
X164950Y615700
X150500Y596000
X171600Y595400
X153500Y574359
X174900Y523300
X156800Y515400
X173700Y513900
X156800Y506900
X173500Y506000
X157100Y500000
X173600Y498800
X169200Y482800
X161900Y463300
X162000Y457600
X161900Y451600
X161600Y445900
X174500Y432000
X162000
X150000Y424000
Y414000
Y404000
Y396000
Y386000
X174000Y316000
X164000
X172000Y310000
X166000Y302000
X176000
X151300Y298200
X162000Y296000
X172000
X173500Y151500
X165300Y145200
X174500Y143500
X176000Y131000
X167000Y130500
X170500Y120500
X171500Y105500
X154000
X167000Y93000
X153000Y90500
X154000Y75500
X164000Y55500
X174000
X155000Y45000
X175000
X165000
X195000
X185000
X200000Y55000
X184000Y55500
X194000
X200000Y65000
Y75000
Y85000
Y100000
X190500Y105000
X180500Y112000
X189500Y120000
X200000
X187500Y130500
X200000Y140000
X186000Y143000
X197500Y151500
X185500
X191900Y167700
X201089Y181700
X191700Y186500
X200500Y195900
X191600Y206900
X201500Y208000
X191800Y221100
X201000Y222500
X191800Y234900
X200500Y235000
X191900Y244600
X202000Y254000
Y264000
Y274000
X201089Y282600
X202000Y295000
X182000Y296000
X184000Y303000
X201089Y305500
X182000Y310000
X201089Y315500
X184500Y325500
X202000Y328000
X187500Y338000
X202000Y340000
X180850Y348800
X202000Y353000
X181100Y364050
X188500Y364100
X202000Y366500
X188300Y368600
X181800Y369000
X201500Y378000
X201089Y388400
X192600Y392600
X192471Y397355
X201500Y397500
X192400Y401900
X201089Y407000
X192300Y410950
X192409Y417655
X200000Y420500
X186600Y425750
X201000Y430500
X200500Y437500
X190239Y447449
X195600Y447500
X190400Y453500
X195500
X189900Y460500
X195000
Y467500
X189900
X188500Y474500
X194500
X199500Y489400
X192000Y490000
X186500Y498000
X192000
X200300Y498100
X192000Y506000
X199800
X186500
X192000Y513500
X186500
X200100Y513600
X186500Y519000
X193600Y519100
X201200Y519200
X190200Y523400
X201089Y523500
X192400Y529400
X201089Y529500
X201500Y535000
X191900Y538200
X192000Y543500
X201500Y544500
X182600Y546900
X190500Y550500
X201500Y552500
X201089Y558000
X201500Y564000
X201089Y570600
X202000Y578000
X194400Y586000
X202000
Y595000
X193700
X180500
X202000Y607500
X194000Y615000
X201500Y621500
X180500Y627771
X194000Y628500
X192600Y633000
X196500Y641500
X192500Y645000
X202000Y650500
X192500Y658500
X184700Y663900
X195000Y670000
X185000Y673500
X202000Y676500
X193100Y679000
X197500Y685000
X188100Y689100
X191500Y692500
X183500Y698000
X197000Y704000
X184500Y708500
X202000Y710000
X191500Y710500
X181000Y715500
X196000Y718500
X191500Y724000
X181000Y729000
X181500Y738500
X195500Y739000
X202000Y740500
X182500Y745000
X191500Y746500
X197500Y753000
X182500Y758500
X191500Y760000
X202000Y765000
X181700Y768400
X194500Y769000
Y782500
X187900Y785300
X202000Y786000
X196000Y789500
X196500Y797000
X202000Y807500
X197000Y815000
X190000Y823500
X196800Y828500
X190500Y831000
X201500Y835500
X192500Y839500
X185000Y843500
X192500Y853000
X184500Y865500
X192000
X184500Y879000
X192000
X187000Y891000
X194000Y893500
Y907000
X185000Y917500
X192000Y921000
Y934500
Y948500
X182000Y950500
X192000Y962000
X192500Y972000
Y985500
X184000Y987500
X195500Y1001000
Y1014500
X182000Y1016000
X193500Y1029000
X182000Y1029500
X182500Y1041500
X193500Y1042500
X181000Y1051000
X190000Y1052000
X195000Y1061000
X183500Y1065500
X195000Y1074500
X181000Y1079500
X195000Y1086500
X187500Y1090000
X201000Y1093000
X181000Y1098500
X194500Y1100500
X187500Y1103500
X201000Y1106500
X181000Y1112500
X183500Y1241500
X191800Y1280900
X195500Y1530500
X189400Y1544100
X194500Y1546000
X197000Y1551500
X193000Y1556500
Y1562500
X187900Y1566600
X189500Y1577000
X198500Y1584000
X182500Y1584500
X192000Y1586000
X182500Y1592000
X197500Y1593000
X191500Y1595000
X182500Y1599400
X199000Y1619500
X190000Y1622000
X191500Y1631000
X198000Y1632500
Y1647500
X196500Y1656000
X197000Y1691500
X184500Y1696500
X182000Y1704000
X197000Y1713000
X181500Y1716500
X182000Y1726000
X197000Y1735500
X185000Y1738500
X197500Y1754000
X183600Y1765100
X197500Y1776500
X186000Y1790000
X196500Y1800500
X185500Y1804500
X198000Y1818500
X183100Y1838300
X197000Y1838500
X185000Y1852500
X197500Y1860000
X194400Y1876700
X196500Y1882000
X201500Y1900500
X195500Y1905000
X201000Y1923000
X190500Y1924000
T03
X31299Y210866
Y220866
Y230866
Y338563
Y348563
Y358563
Y903917
Y913917
Y923917
Y1044587
Y1054587
Y1064587
Y1609941
Y1619941
Y1629941
Y1737638
Y1747638
Y1757638
T04
X15906Y48110
Y58110
Y68110
Y78110
Y88110
Y481339
Y491339
Y501339
Y511339
Y521339
Y741181
Y751181
Y761181
Y771181
Y781181
Y1187323
Y1197323
Y1207323
Y1217323
Y1227323
X165000Y1370500
Y1380500
Y1390500
X15906Y1447165
Y1457165
Y1467165
Y1477165
Y1487165
X138937Y1778819
X128937
X118937
X15906Y1880394
Y1890394
Y1900394
Y1910394
Y1920394
T05
X80709Y161889
Y171889
Y181889
Y191889
Y204409
Y214409
Y224409
Y234409
Y244409
Y256929
Y266929
Y276929
Y286929
X90709
Y276929
Y266929
Y256929
Y244409
Y234409
Y224409
Y214409
Y204409
Y191889
Y181889
Y171889
Y161889
X100709
Y171889
Y181889
Y191889
Y204409
Y214409
Y224409
Y234409
Y244409
Y256929
Y266929
Y276929
Y286929
X110709
Y276929
Y266929
Y256929
Y244409
Y234409
Y224409
Y214409
Y204409
Y191889
Y181889
Y171889
Y161889
X149606
Y171889
Y181889
Y191889
Y204409
Y214409
Y224409
Y234409
Y244409
Y256929
Y266929
Y276929
Y286929
X159606
Y276929
Y266929
Y256929
Y244409
Y234409
Y224409
Y214409
Y204409
Y191889
Y181889
Y171889
Y161889
X169606
Y171889
Y181889
Y191889
Y204409
Y214409
Y224409
Y234409
Y244409
Y256929
Y266929
Y276929
Y286929
X179606
Y276929
Y266929
Y256929
Y244409
Y234409
Y224409
Y214409
Y204409
Y191889
Y181889
Y171889
Y161889
T06
X179134Y78740
X179133Y570866
X27559Y629921
X179134Y1161417
X17716Y1338583
X27559Y1811023
T07
X27559Y157480
X179134Y1889764
T08
X178937Y1328740
X161417Y1747835
X96457
Y1823031
X161417
T09
X80709Y139409
X149606
Y309409
X80709
T10
X47244Y68110
Y501338
Y761181
Y1207323
Y1467165
Y1900393
T11
X80709Y119409
X149606
Y329409
X80709
T12
X-222440Y19685
X643700
Y1948818
X-222440
T13
X29921Y24803
Y111417
Y458031
Y544646
Y717874
Y804488
X30000Y1164000
X29921Y1250630
Y1423858
Y1510472
Y1857086
Y1943701
M30
